(kicad_pcb
	(version 20260206)
	(generator "pcbnew")
	(generator_version "10.0")
	(general
		(thickness 1.6)
		(legacy_teardrops no)
	)
	(paper "A4")
	(title_block
		(title "01162023_DA0F0TEBIF0_F0T_Expander_BD_F_brd_V02_OCP.brd")
		(comment 1 "Grand Teton / footprints 823-829 of 9728")
	)
	(layers
		(0 "F.Cu" signal "TOP")
		(4 "In1.Cu" signal "GND")
		(6 "In2.Cu" signal "VCC")
		(8 "In3.Cu" signal "VCC1")
		(10 "In4.Cu" signal "GND1")
		(12 "In5.Cu" signal "IN1")
		(14 "In6.Cu" signal "GND2")
		(16 "In7.Cu" signal "IN2")
		(18 "In8.Cu" signal "GND3")
		(20 "In9.Cu" signal "IN3")
		(22 "In10.Cu" signal "GND4")
		(24 "In11.Cu" signal "IN4")
		(26 "In12.Cu" signal "GND5")
		(28 "In13.Cu" signal "IN5")
		(30 "In14.Cu" signal "GND6")
		(32 "In15.Cu" signal "IN6")
		(34 "In16.Cu" signal "GND7")
		(2 "B.Cu" signal "BOTTOM")
		(9 "F.Adhes" user "F.Adhesive")
		(11 "B.Adhes" user "B.Adhesive")
		(13 "F.Paste" user "Package Geometry/Pastemask Top")
		(15 "B.Paste" user "Package Geometry/Pastemask Bottom")
		(5 "F.SilkS" user "Ref Des/Silkscreen Top")
		(7 "B.SilkS" user "Ref Des/Silkscreen Bottom")
		(1 "F.Mask" user "Board Geometry/Soldermask Top")
		(3 "B.Mask" user "Board Geometry/Soldermask Bottom")
		(17 "Dwgs.User" user "User.Drawings")
		(19 "Cmts.User" user "User.Comments")
		(21 "Eco1.User" user "User.Eco1")
		(23 "Eco2.User" user "User.Eco2")
		(25 "Edge.Cuts" user "Board Geometry/Outline")
		(27 "Margin" user)
		(31 "F.CrtYd" user "Package Geometry/Place Bound Top")
		(29 "B.CrtYd" user "Package Geometry/Place Bound Bottom")
		(35 "F.Fab" user "Ref Des/Assembly Top")
		(33 "B.Fab" user "Ref Des/Assembly Bottom")
	)
	(footprint ""
		(layer "F.Cu")
		(at 205.598522 -297.46448)
		(property "Reference" "R3941"
			(at 0 0 0)
			(layer "F.SilkS")
			(hide yes)
			(effects
				(font
					(size 1.27 1.27)
				)
			)
		)
		(property "Value" ""
			(at 0 0 0)
			(layer "F.Fab")
			(effects
				(font
					(size 1.27 1.27)
				)
			)
		)
		(duplicate_pad_numbers_are_jumpers no)
		(fp_line
			(start -0.7874 -0.4064)
			(end 0.7874 -0.4064)
			(stroke
				(width 0.1524)
				(type default)
			)
			(layer "F.SilkS")
		)
		(fp_line
			(start -0.7874 0.4064)
			(end -0.7874 -0.4064)
			(stroke
				(width 0.1524)
				(type default)
			)
			(layer "F.SilkS")
		)
		(fp_line
			(start 0.7874 -0.4064)
			(end 0.7874 0.4064)
			(stroke
				(width 0.1524)
				(type default)
			)
			(layer "F.SilkS")
		)
		(fp_line
			(start 0.7874 0.4064)
			(end -0.7874 0.4064)
			(stroke
				(width 0.1524)
				(type default)
			)
			(layer "F.SilkS")
		)
		(fp_line
			(start -0.67945 -0.305054)
			(end -0.12065 -0.305054)
			(stroke
				(width 0.1)
				(type default)
			)
			(layer "F.Fab")
		)
		(fp_line
			(start -0.67945 0.3048)
			(end -0.67945 -0.305054)
			(stroke
				(width 0.1)
				(type default)
			)
			(layer "F.Fab")
		)
		(fp_line
			(start -0.12065 -0.305054)
			(end -0.12065 -0.2794)
			(stroke
				(width 0.1)
				(type default)
			)
			(layer "F.Fab")
		)
		(fp_line
			(start -0.12065 -0.2794)
			(end 0.12065 -0.2794)
			(stroke
				(width 0.1)
				(type default)
			)
			(layer "F.Fab")
		)
		(fp_line
			(start -0.12065 0.2794)
			(end -0.12065 0.3048)
			(stroke
				(width 0.1)
				(type default)
			)
			(layer "F.Fab")
		)
		(fp_line
			(start -0.12065 0.3048)
			(end -0.67945 0.3048)
			(stroke
				(width 0.1)
				(type default)
			)
			(layer "F.Fab")
		)
		(fp_line
			(start 0.120396 0.2794)
			(end -0.12065 0.2794)
			(stroke
				(width 0.1)
				(type default)
			)
			(layer "F.Fab")
		)
		(fp_line
			(start 0.120396 0.3048)
			(end 0.120396 0.2794)
			(stroke
				(width 0.1)
				(type default)
			)
			(layer "F.Fab")
		)
		(fp_line
			(start 0.12065 -0.3048)
			(end 0.67945 -0.3048)
			(stroke
				(width 0.1)
				(type default)
			)
			(layer "F.Fab")
		)
		(fp_line
			(start 0.12065 -0.2794)
			(end 0.12065 -0.3048)
			(stroke
				(width 0.1)
				(type default)
			)
			(layer "F.Fab")
		)
		(fp_line
			(start 0.67945 -0.3048)
			(end 0.67945 0.3048)
			(stroke
				(width 0.1)
				(type default)
			)
			(layer "F.Fab")
		)
		(fp_line
			(start 0.67945 0.3048)
			(end 0.120396 0.3048)
			(stroke
				(width 0.1)
				(type default)
			)
			(layer "F.Fab")
		)
		(pad "1" smd circle
			(at -0.40005 0)
			(size 0 0)
			(layers "F.Cu" "F.Mask" "F.Paste")
			(net "SMB_PEX1_HOST_LS_SDA")
		)
		(pad "2" smd circle
			(at 0.40005 0)
			(size 0 0)
			(layers "F.Cu" "F.Mask" "F.Paste")
			(net "I2C_PEX1_HOST_R_SDA")
		)
	)
	(footprint ""
		(layer "F.Cu")
		(at 384.938524 -134.923276)
		(property "Reference" "C669"
			(at 0 0 0)
			(layer "F.SilkS")
			(hide yes)
			(effects
				(font
					(size 1.27 1.27)
				)
			)
		)
		(property "Value" ""
			(at 0 0 0)
			(layer "F.Fab")
			(effects
				(font
					(size 1.27 1.27)
				)
			)
		)
		(duplicate_pad_numbers_are_jumpers no)
		(fp_line
			(start -0.299974 -0.150114)
			(end 0.299974 -0.150114)
			(stroke
				(width 0.1)
				(type default)
			)
			(layer "F.Fab")
		)
		(fp_line
			(start -0.299974 0.150114)
			(end -0.299974 -0.150114)
			(stroke
				(width 0.1)
				(type default)
			)
			(layer "F.Fab")
		)
		(fp_line
			(start 0.299974 -0.150114)
			(end 0.299974 0.150114)
			(stroke
				(width 0.1)
				(type default)
			)
			(layer "F.Fab")
		)
		(fp_line
			(start 0.299974 0.150114)
			(end -0.299974 0.150114)
			(stroke
				(width 0.1)
				(type default)
			)
			(layer "F.Fab")
		)
		(pad "1" smd rect
			(at -0.2667 0)
			(size 0.3048 0.381)
			(layers "F.Cu" "F.Mask" "F.Paste")
			(net "P5E_PEX3_STN1_TX_DN<30>")
		)
		(pad "2" smd rect
			(at 0.2667 0)
			(size 0.3048 0.381)
			(layers "F.Cu" "F.Mask" "F.Paste")
			(net "P5E_PEX3_STN1_TX_C_DN<30>")
		)
	)
	(footprint ""
		(layer "F.Cu")
		(at 436.03799 -291.102034 180)
		(property "Reference" "R6399"
			(at 0 0 180)
			(layer "F.SilkS")
			(hide yes)
			(effects
				(font
					(size 1.27 1.27)
				)
			)
		)
		(property "Value" ""
			(at 0 0 180)
			(layer "F.Fab")
			(effects
				(font
					(size 1.27 1.27)
				)
			)
		)
		(duplicate_pad_numbers_are_jumpers no)
		(fp_line
			(start 0.7874 0.4064)
			(end -0.7874 0.4064)
			(stroke
				(width 0.1524)
				(type default)
			)
			(layer "F.SilkS")
		)
		(fp_line
			(start 0.7874 -0.4064)
			(end 0.7874 0.4064)
			(stroke
				(width 0.1524)
				(type default)
			)
			(layer "F.SilkS")
		)
		(fp_line
			(start -0.7874 0.4064)
			(end -0.7874 -0.4064)
			(stroke
				(width 0.1524)
				(type default)
			)
			(layer "F.SilkS")
		)
		(fp_line
			(start -0.7874 -0.4064)
			(end 0.7874 -0.4064)
			(stroke
				(width 0.1524)
				(type default)
			)
			(layer "F.SilkS")
		)
		(fp_line
			(start 0.67945 0.3048)
			(end 0.120396 0.3048)
			(stroke
				(width 0.1)
				(type default)
			)
			(layer "F.Fab")
		)
		(fp_line
			(start 0.67945 -0.3048)
			(end 0.67945 0.3048)
			(stroke
				(width 0.1)
				(type default)
			)
			(layer "F.Fab")
		)
		(fp_line
			(start 0.12065 -0.2794)
			(end 0.12065 -0.3048)
			(stroke
				(width 0.1)
				(type default)
			)
			(layer "F.Fab")
		)
		(fp_line
			(start 0.12065 -0.3048)
			(end 0.67945 -0.3048)
			(stroke
				(width 0.1)
				(type default)
			)
			(layer "F.Fab")
		)
		(fp_line
			(start 0.120396 0.3048)
			(end 0.120396 0.2794)
			(stroke
				(width 0.1)
				(type default)
			)
			(layer "F.Fab")
		)
		(fp_line
			(start 0.120396 0.2794)
			(end -0.12065 0.2794)
			(stroke
				(width 0.1)
				(type default)
			)
			(layer "F.Fab")
		)
		(fp_line
			(start -0.12065 0.3048)
			(end -0.67945 0.3048)
			(stroke
				(width 0.1)
				(type default)
			)
			(layer "F.Fab")
		)
		(fp_line
			(start -0.12065 0.2794)
			(end -0.12065 0.3048)
			(stroke
				(width 0.1)
				(type default)
			)
			(layer "F.Fab")
		)
		(fp_line
			(start -0.12065 -0.2794)
			(end 0.12065 -0.2794)
			(stroke
				(width 0.1)
				(type default)
			)
			(layer "F.Fab")
		)
		(fp_line
			(start -0.12065 -0.305054)
			(end -0.12065 -0.2794)
			(stroke
				(width 0.1)
				(type default)
			)
			(layer "F.Fab")
		)
		(fp_line
			(start -0.67945 0.3048)
			(end -0.67945 -0.305054)
			(stroke
				(width 0.1)
				(type default)
			)
			(layer "F.Fab")
		)
		(fp_line
			(start -0.67945 -0.305054)
			(end -0.12065 -0.305054)
			(stroke
				(width 0.1)
				(type default)
			)
			(layer "F.Fab")
		)
		(pad "1" smd circle
			(at -0.40005 0 180)
			(size 0 0)
			(layers "F.Cu" "F.Mask" "F.Paste")
			(net "GND")
		)
		(pad "2" smd circle
			(at 0.40005 0 180)
			(size 0 0)
			(layers "F.Cu" "F.Mask" "F.Paste")
			(net "RST_PEX3_PERST_R_N")
		)
	)
	(footprint ""
		(layer "F.Cu")
		(at 313.075066 -64.102234 180)
		(property "Reference" "PR7086"
			(at 0 0 180)
			(layer "F.SilkS")
			(hide yes)
			(effects
				(font
					(size 1.27 1.27)
				)
			)
		)
		(property "Value" ""
			(at 0 0 180)
			(layer "F.Fab")
			(effects
				(font
					(size 1.27 1.27)
				)
			)
		)
		(duplicate_pad_numbers_are_jumpers no)
		(fp_line
			(start 0.7874 0.4064)
			(end -0.7874 0.4064)
			(stroke
				(width 0.1524)
				(type default)
			)
			(layer "F.SilkS")
		)
		(fp_line
			(start 0.7874 -0.4064)
			(end 0.7874 0.4064)
			(stroke
				(width 0.1524)
				(type default)
			)
			(layer "F.SilkS")
		)
		(fp_line
			(start -0.7874 0.4064)
			(end -0.7874 -0.4064)
			(stroke
				(width 0.1524)
				(type default)
			)
			(layer "F.SilkS")
		)
		(fp_line
			(start -0.7874 -0.4064)
			(end 0.7874 -0.4064)
			(stroke
				(width 0.1524)
				(type default)
			)
			(layer "F.SilkS")
		)
		(fp_line
			(start 0.67945 0.3048)
			(end 0.120396 0.3048)
			(stroke
				(width 0.1)
				(type default)
			)
			(layer "F.Fab")
		)
		(fp_line
			(start 0.67945 -0.3048)
			(end 0.67945 0.3048)
			(stroke
				(width 0.1)
				(type default)
			)
			(layer "F.Fab")
		)
		(fp_line
			(start 0.12065 -0.2794)
			(end 0.12065 -0.3048)
			(stroke
				(width 0.1)
				(type default)
			)
			(layer "F.Fab")
		)
		(fp_line
			(start 0.12065 -0.3048)
			(end 0.67945 -0.3048)
			(stroke
				(width 0.1)
				(type default)
			)
			(layer "F.Fab")
		)
		(fp_line
			(start 0.120396 0.3048)
			(end 0.120396 0.2794)
			(stroke
				(width 0.1)
				(type default)
			)
			(layer "F.Fab")
		)
		(fp_line
			(start 0.120396 0.2794)
			(end -0.12065 0.2794)
			(stroke
				(width 0.1)
				(type default)
			)
			(layer "F.Fab")
		)
		(fp_line
			(start -0.12065 0.3048)
			(end -0.67945 0.3048)
			(stroke
				(width 0.1)
				(type default)
			)
			(layer "F.Fab")
		)
		(fp_line
			(start -0.12065 0.2794)
			(end -0.12065 0.3048)
			(stroke
				(width 0.1)
				(type default)
			)
			(layer "F.Fab")
		)
		(fp_line
			(start -0.12065 -0.2794)
			(end 0.12065 -0.2794)
			(stroke
				(width 0.1)
				(type default)
			)
			(layer "F.Fab")
		)
		(fp_line
			(start -0.12065 -0.305054)
			(end -0.12065 -0.2794)
			(stroke
				(width 0.1)
				(type default)
			)
			(layer "F.Fab")
		)
		(fp_line
			(start -0.67945 0.3048)
			(end -0.67945 -0.305054)
			(stroke
				(width 0.1)
				(type default)
			)
			(layer "F.Fab")
		)
		(fp_line
			(start -0.67945 -0.305054)
			(end -0.12065 -0.305054)
			(stroke
				(width 0.1)
				(type default)
			)
			(layer "F.Fab")
		)
		(pad "1" smd circle
			(at -0.40005 0 180)
			(size 0 0)
			(layers "F.Cu" "F.Mask" "F.Paste")
			(net "P12V_SSD11_PG_G1")
		)
		(pad "2" smd circle
			(at 0.40005 0 180)
			(size 0 0)
			(layers "F.Cu" "F.Mask" "F.Paste")
			(net "GND")
		)
	)
	(footprint ""
		(layer "F.Cu")
		(at 350.380554 -82.644234)
		(property "Reference" "R1600"
			(at 0 0 0)
			(layer "F.SilkS")
			(hide yes)
			(effects
				(font
					(size 1.27 1.27)
				)
			)
		)
		(property "Value" ""
			(at 0 0 0)
			(layer "F.Fab")
			(effects
				(font
					(size 1.27 1.27)
				)
			)
		)
		(duplicate_pad_numbers_are_jumpers no)
		(fp_line
			(start -0.7874 -0.4064)
			(end 0.7874 -0.4064)
			(stroke
				(width 0.1524)
				(type default)
			)
			(layer "F.SilkS")
		)
		(fp_line
			(start -0.7874 0.4064)
			(end -0.7874 -0.4064)
			(stroke
				(width 0.1524)
				(type default)
			)
			(layer "F.SilkS")
		)
		(fp_line
			(start 0.7874 -0.4064)
			(end 0.7874 0.4064)
			(stroke
				(width 0.1524)
				(type default)
			)
			(layer "F.SilkS")
		)
		(fp_line
			(start 0.7874 0.4064)
			(end -0.7874 0.4064)
			(stroke
				(width 0.1524)
				(type default)
			)
			(layer "F.SilkS")
		)
		(fp_line
			(start -0.67945 -0.305054)
			(end -0.12065 -0.305054)
			(stroke
				(width 0.1)
				(type default)
			)
			(layer "F.Fab")
		)
		(fp_line
			(start -0.67945 0.3048)
			(end -0.67945 -0.305054)
			(stroke
				(width 0.1)
				(type default)
			)
			(layer "F.Fab")
		)
		(fp_line
			(start -0.12065 -0.305054)
			(end -0.12065 -0.2794)
			(stroke
				(width 0.1)
				(type default)
			)
			(layer "F.Fab")
		)
		(fp_line
			(start -0.12065 -0.2794)
			(end 0.12065 -0.2794)
			(stroke
				(width 0.1)
				(type default)
			)
			(layer "F.Fab")
		)
		(fp_line
			(start -0.12065 0.2794)
			(end -0.12065 0.3048)
			(stroke
				(width 0.1)
				(type default)
			)
			(layer "F.Fab")
		)
		(fp_line
			(start -0.12065 0.3048)
			(end -0.67945 0.3048)
			(stroke
				(width 0.1)
				(type default)
			)
			(layer "F.Fab")
		)
		(fp_line
			(start 0.120396 0.2794)
			(end -0.12065 0.2794)
			(stroke
				(width 0.1)
				(type default)
			)
			(layer "F.Fab")
		)
		(fp_line
			(start 0.120396 0.3048)
			(end 0.120396 0.2794)
			(stroke
				(width 0.1)
				(type default)
			)
			(layer "F.Fab")
		)
		(fp_line
			(start 0.12065 -0.3048)
			(end 0.67945 -0.3048)
			(stroke
				(width 0.1)
				(type default)
			)
			(layer "F.Fab")
		)
		(fp_line
			(start 0.12065 -0.2794)
			(end 0.12065 -0.3048)
			(stroke
				(width 0.1)
				(type default)
			)
			(layer "F.Fab")
		)
		(fp_line
			(start 0.67945 -0.3048)
			(end 0.67945 0.3048)
			(stroke
				(width 0.1)
				(type default)
			)
			(layer "F.Fab")
		)
		(fp_line
			(start 0.67945 0.3048)
			(end 0.120396 0.3048)
			(stroke
				(width 0.1)
				(type default)
			)
			(layer "F.Fab")
		)
		(pad "1" smd circle
			(at -0.40005 0)
			(size 0 0)
			(layers "F.Cu" "F.Mask" "F.Paste")
			(net "P3V3_AUX")
		)
		(pad "2" smd circle
			(at 0.40005 0)
			(size 0 0)
			(layers "F.Cu" "F.Mask" "F.Paste")
			(net "SMB_BIC_I2C9_MUX1_SSD11_R_SDA")
		)
	)
	(footprint ""
		(layer "F.Cu")
		(at 80.53959 -137.645648)
		(property "Reference" "R56"
			(at 0 0 0)
			(layer "F.SilkS")
			(hide yes)
			(effects
				(font
					(size 1.27 1.27)
				)
			)
		)
		(property "Value" ""
			(at 0 0 0)
			(layer "F.Fab")
			(effects
				(font
					(size 1.27 1.27)
				)
			)
		)
		(duplicate_pad_numbers_are_jumpers no)
		(fp_line
			(start -0.7874 -0.4064)
			(end 0.7874 -0.4064)
			(stroke
				(width 0.1524)
				(type default)
			)
			(layer "F.SilkS")
		)
		(fp_line
			(start -0.7874 0.4064)
			(end -0.7874 -0.4064)
			(stroke
				(width 0.1524)
				(type default)
			)
			(layer "F.SilkS")
		)
		(fp_line
			(start 0.7874 -0.4064)
			(end 0.7874 0.4064)
			(stroke
				(width 0.1524)
				(type default)
			)
			(layer "F.SilkS")
		)
		(fp_line
			(start 0.7874 0.4064)
			(end -0.7874 0.4064)
			(stroke
				(width 0.1524)
				(type default)
			)
			(layer "F.SilkS")
		)
		(fp_line
			(start -0.67945 -0.305054)
			(end -0.12065 -0.305054)
			(stroke
				(width 0.1)
				(type default)
			)
			(layer "F.Fab")
		)
		(fp_line
			(start -0.67945 0.3048)
			(end -0.67945 -0.305054)
			(stroke
				(width 0.1)
				(type default)
			)
			(layer "F.Fab")
		)
		(fp_line
			(start -0.12065 -0.305054)
			(end -0.12065 -0.2794)
			(stroke
				(width 0.1)
				(type default)
			)
			(layer "F.Fab")
		)
		(fp_line
			(start -0.12065 -0.2794)
			(end 0.12065 -0.2794)
			(stroke
				(width 0.1)
				(type default)
			)
			(layer "F.Fab")
		)
		(fp_line
			(start -0.12065 0.2794)
			(end -0.12065 0.3048)
			(stroke
				(width 0.1)
				(type default)
			)
			(layer "F.Fab")
		)
		(fp_line
			(start -0.12065 0.3048)
			(end -0.67945 0.3048)
			(stroke
				(width 0.1)
				(type default)
			)
			(layer "F.Fab")
		)
		(fp_line
			(start 0.120396 0.2794)
			(end -0.12065 0.2794)
			(stroke
				(width 0.1)
				(type default)
			)
			(layer "F.Fab")
		)
		(fp_line
			(start 0.120396 0.3048)
			(end 0.120396 0.2794)
			(stroke
				(width 0.1)
				(type default)
			)
			(layer "F.Fab")
		)
		(fp_line
			(start 0.12065 -0.3048)
			(end 0.67945 -0.3048)
			(stroke
				(width 0.1)
				(type default)
			)
			(layer "F.Fab")
		)
		(fp_line
			(start 0.12065 -0.2794)
			(end 0.12065 -0.3048)
			(stroke
				(width 0.1)
				(type default)
			)
			(layer "F.Fab")
		)
		(fp_line
			(start 0.67945 -0.3048)
			(end 0.67945 0.3048)
			(stroke
				(width 0.1)
				(type default)
			)
			(layer "F.Fab")
		)
		(fp_line
			(start 0.67945 0.3048)
			(end 0.120396 0.3048)
			(stroke
				(width 0.1)
				(type default)
			)
			(layer "F.Fab")
		)
		(pad "1" smd circle
			(at -0.40005 0)
			(size 0 0)
			(layers "F.Cu" "F.Mask" "F.Paste")
			(net "PRSNTB0_NIC1_N")
		)
		(pad "2" smd circle
			(at 0.40005 0)
			(size 0 0)
			(layers "F.Cu" "F.Mask" "F.Paste")
			(net "P3V3_AUX")
		)
	)
	(footprint ""
		(layer "F.Cu")
		(at 221.251272 -141.910562 180)
		(property "Reference" "C2807"
			(at 0 0 180)
			(layer "F.SilkS")
			(hide yes)
			(effects
				(font
					(size 1.27 1.27)
				)
			)
		)
		(property "Value" ""
			(at 0 0 180)
			(layer "F.Fab")
			(effects
				(font
					(size 1.27 1.27)
				)
			)
		)
		(duplicate_pad_numbers_are_jumpers no)
		(fp_line
			(start 0.7874 0.4064)
			(end -0.7874 0.4064)
			(stroke
				(width 0.1524)
				(type default)
			)
			(layer "F.SilkS")
		)
		(fp_line
			(start 0.7874 -0.4064)
			(end 0.7874 0.4064)
			(stroke
				(width 0.1524)
				(type default)
			)
			(layer "F.SilkS")
		)
		(fp_line
			(start -0.7874 0.4064)
			(end -0.7874 -0.4064)
			(stroke
				(width 0.1524)
				(type default)
			)
			(layer "F.SilkS")
		)
		(fp_line
			(start -0.7874 -0.4064)
			(end 0.7874 -0.4064)
			(stroke
				(width 0.1524)
				(type default)
			)
			(layer "F.SilkS")
		)
		(fp_line
			(start 0.67945 0.3048)
			(end 0.120396 0.3048)
			(stroke
				(width 0.1)
				(type default)
			)
			(layer "F.Fab")
		)
		(fp_line
			(start 0.67945 -0.3048)
			(end 0.67945 0.3048)
			(stroke
				(width 0.1)
				(type default)
			)
			(layer "F.Fab")
		)
		(fp_line
			(start 0.12065 -0.2794)
			(end 0.12065 -0.3048)
			(stroke
				(width 0.1)
				(type default)
			)
			(layer "F.Fab")
		)
		(fp_line
			(start 0.12065 -0.3048)
			(end 0.67945 -0.3048)
			(stroke
				(width 0.1)
				(type default)
			)
			(layer "F.Fab")
		)
		(fp_line
			(start 0.120396 0.3048)
			(end 0.120396 0.2794)
			(stroke
				(width 0.1)
				(type default)
			)
			(layer "F.Fab")
		)
		(fp_line
			(start 0.120396 0.2794)
			(end -0.12065 0.2794)
			(stroke
				(width 0.1)
				(type default)
			)
			(layer "F.Fab")
		)
		(fp_line
			(start -0.12065 0.3048)
			(end -0.67945 0.3048)
			(stroke
				(width 0.1)
				(type default)
			)
			(layer "F.Fab")
		)
		(fp_line
			(start -0.12065 0.2794)
			(end -0.12065 0.3048)
			(stroke
				(width 0.1)
				(type default)
			)
			(layer "F.Fab")
		)
		(fp_line
			(start -0.12065 -0.2794)
			(end 0.12065 -0.2794)
			(stroke
				(width 0.1)
				(type default)
			)
			(layer "F.Fab")
		)
		(fp_line
			(start -0.12065 -0.305054)
			(end -0.12065 -0.2794)
			(stroke
				(width 0.1)
				(type default)
			)
			(layer "F.Fab")
		)
		(fp_line
			(start -0.67945 0.3048)
			(end -0.67945 -0.305054)
			(stroke
				(width 0.1)
				(type default)
			)
			(layer "F.Fab")
		)
		(fp_line
			(start -0.67945 -0.305054)
			(end -0.12065 -0.305054)
			(stroke
				(width 0.1)
				(type default)
			)
			(layer "F.Fab")
		)
		(pad "1" smd circle
			(at -0.40005 0 180)
			(size 0 0)
			(layers "F.Cu" "F.Mask" "F.Paste")
			(net "FM_CK440_PEX_DEV_25M_EN")
		)
		(pad "2" smd circle
			(at 0.40005 0 180)
			(size 0 0)
			(layers "F.Cu" "F.Mask" "F.Paste")
			(net "GND")
		)
	)
)
